FILE_TYPE = CONNECTIVITY;
{Allegro Design Entry HDL 17.4-2019 S026 (4007227) 1/17/2022}
"PAGE_NUMBER" = 369;
0"NC";
1"GND\g";
2"GND\g";
3"GND\g";
4"GND\g";
5"GND\g";
6"GND\g";
7"GND\g";
8"GND\g";
9"GND\g";
10"GND\g";
11"GND\g";
12"GND\g";
13"P3V3_AUX\g";
14"P5V\g";
15"GND\g";
16"P3V3\g";
17"P3V3_AUX\g";
18"GND\g";
19"GND\g";
20"GND\g";
21"GND\g";
22"GND\g";
23"GND\g";
24"GND\g";
25"GND\g";
26"GND\g";
27"P12V_AUX\g";
28"GND\g";
29"GND\g";
30"GND\g";
31"GND\g";
32"GND\g";
33"P3V3_AUX\g";
34"GND\g";
35"GND\g";
36"P3V3_PDB_AUX_ADC_MAM"CDS_PHYS_NET_NAME"P3V3_PDB_AUX_ADC_MAM";
37"P3V3_PDB_AUX_ADC_TIC"CDS_PHYS_NET_NAME"P3V3_PDB_AUX_ADC_TIC";
38"P12V_E1S_0_ISENSE_TIC"CDS_PHYS_NET_NAME"P12V_E1S_0_ISENSE_TIC";
39"P12V_E1S_0_ISENSE_MAM"CDS_PHYS_NET_NAME"P12V_E1S_0_ISENSE_MAM";
40"P12V_OCP_V3_2_ISENSE_TIC"CDS_PHYS_NET_NAME"P12V_OCP_V3_2_ISENSE_TIC";
41"P5V_ADC_MAM"CDS_PHYS_NET_NAME"P5V_ADC_MAM";
42"P12V_OCP_SFF_ISENSE_MAM"CDS_PHYS_NET_NAME"P12V_OCP_SFF_ISENSE_MAM";
43"P12V_OCP_V3_2_ISENSE_MAM_TIC"CDS_PHYS_NET_NAME"P12V_OCP_V3_2_ISENSE_MAM_TIC";
44"P12V_OCP_V3_2_ISENSE_MPS_TIC"CDS_PHYS_NET_NAME"P12V_OCP_V3_2_ISENSE_MPS_TIC";
45"P12V_E1S_0_ISENSE_MAM_MAM"CDS_PHYS_NET_NAME"P12V_E1S_0_ISENSE_MAM_MAM";
46"P12V_E1S_0_ISENSE_MPS_MAM"CDS_PHYS_NET_NAME"P12V_E1S_0_ISENSE_MPS_MAM";
47"P12V_E1S_0_ISENSE_MAM_TIC"CDS_PHYS_NET_NAME"P12V_E1S_0_ISENSE_MAM_TIC";
48"P5V_ADC"CDS_PHYS_NET_NAME"P5V_ADC";
49"P12V_E1S_0_ISENSE_MPS_TIC"CDS_PHYS_NET_NAME"P12V_E1S_0_ISENSE_MPS_TIC";
50"ADC128_VREF"CDS_PHYS_NET_NAME"ADC128_VREF";
51"ADC128_A1"CDS_PHYS_NET_NAME"ADC128_A1";
52"ADC128_A0"CDS_PHYS_NET_NAME"ADC128_A0";
53"P12V_E1S_0_ISENSE_TIC"CDS_PHYS_NET_NAME"P12V_E1S_0_ISENSE_TIC";
54"P12V_OCP_V3_2_ISENSE_MAM"CDS_PHYS_NET_NAME"P12V_OCP_V3_2_ISENSE_MAM";
55"P12V_OCP_SFF_ISENSE_MPS_MAM"CDS_PHYS_NET_NAME"P12V_OCP_SFF_ISENSE_MPS_MAM";
56"P12V_OCP_SFF_ISENSE_TIC"CDS_PHYS_NET_NAME"P12V_OCP_SFF_ISENSE_TIC";
57"P12V_OCP_SFF_ISENSE_MPS_TIC"CDS_PHYS_NET_NAME"P12V_OCP_SFF_ISENSE_MPS_TIC";
58"P3V3_MAX11617_VDD";
59"MAX11617_VREF_R";
60"MAX11617_VREF";
61"GND\g";
62"SMB_SEN_MAM_3V3AUX_SCL"CDS_PHYS_NET_NAME"SMB_SEN_TIC_3V3AUX_SCL";
63"GND\g";
64"P3V3_AUX\g";
65"GND\g";
66"P12V_OCP_V3_2_ISENSE_MPS_MAM"CDS_PHYS_NET_NAME"P12V_OCP_V3_2_ISENSE_MPS_MAM";
67"P12V_OCP_SFF_ISENSE_MAM_MAM"CDS_PHYS_NET_NAME"P12V_OCP_SFF_ISENSE_MAM_MAM";
68"P1V581_PDB_ADC"CDS_PHYS_NET_NAME"P1V581_PDB_ADC";
69"P12V_AUX_ADC_MAM"CDS_PHYS_NET_NAME"P12V_AUX_ADC_MAM";
70"P3V3_PDB_AUX_ADC";
71"P12V_AUX_ADC_TIC"CDS_PHYS_NET_NAME"P12V_AUX_ADC_TIC";
72"P12V_AUX_ADC"CDS_PHYS_NET_NAME"P12V_AUX_ADC";
73"P5V_ADC_TIC"CDS_PHYS_NET_NAME"P5V_ADC_TIC";
74"P3V3_ADC_MAM"CDS_PHYS_NET_NAME"P3V3_ADC_MAM";
75"P3V3_ADC_TIC"CDS_PHYS_NET_NAME"P3V3_ADC_TIC";
76"P3V3_AUX_ADC_TIC"CDS_PHYS_NET_NAME"P3V3_AUX_ADC_TIC";
77"P3V3_AUX_ADC_MAM"CDS_PHYS_NET_NAME"P3V3_AUX_ADC_MAM";
78"P3V3_ADC"CDS_PHYS_NET_NAME"P3V3_ADC";
79"P3V3_AUX_ADC"CDS_PHYS_NET_NAME"P3V3_AUX_ADC";
80"P3V3_AUX_ADC_MAM"CDS_PHYS_NET_NAME"P3V3_AUX_ADC_MAM";
81"P3V3_ADC_MAM"CDS_PHYS_NET_NAME"P3V3_ADC_MAM";
82"P12V_E1S_0_ISENSE_MAM"CDS_PHYS_NET_NAME"P12V_E1S_0_ISENSE_MAM";
83"SMB_SEN_MAM_3V3AUX_SCL"CDS_PHYS_NET_NAME"SMB_SEN_TIC_3V3AUX_SCL";
84"SMB_SEN_MAM_3V3AUX_SDA"CDS_PHYS_NET_NAME"SMB_SEN_TIC_3V3AUX_SDA";
85"SMB_SEN_MAM_3V3AUX_SDA"CDS_PHYS_NET_NAME"SMB_SEN_TIC_3V3AUX_SDA";
86"SMB_SCM_2_R4_SDA"CDS_PHYS_NET_NAME"SMB_VR_3V3AUX_SDA_R1";
87"SMB_SCM_2_R4_SCL"CDS_PHYS_NET_NAME"SMB_VR_3V3AUX_SCL_R1";
88"P5V_ADC_MAM"CDS_PHYS_NET_NAME"P5V_ADC_MAM";
89"P12V_OCP_SFF_ISENSE_MAM"CDS_PHYS_NET_NAME"P12V_OCP_SFF_ISENSE_MAM";
90"P12V_AUX_ADC_MAM"CDS_PHYS_NET_NAME"P12V_AUX_ADC_MAM";
91"P12V_OCP_V3_2_ISENSE_MAM"CDS_PHYS_NET_NAME"P12V_OCP_V3_2_ISENSE_MAM";
92"P3V3_ADC128_VCC";
93"P12V_AUX_ADC_TIC"CDS_PHYS_NET_NAME"P12V_AUX_ADC_TIC";
94"P12V_OCP_SFF_ISENSE_TIC"CDS_PHYS_NET_NAME"P12V_OCP_SFF_ISENSE_TIC";
95"SMB_SEN_TIC_3V3AUX_SCL"CDS_PHYS_NET_NAME"SMB_SEN_TIC_3V3AUX_SCL";
96"P12V_OCP_V3_2_ISENSE_TIC"CDS_PHYS_NET_NAME"P12V_OCP_V3_2_ISENSE_TIC";
97"P3V3_ADC_TIC"CDS_PHYS_NET_NAME"P3V3_ADC_TIC";
98"P3V3_AUX_ADC_TIC"CDS_PHYS_NET_NAME"P3V3_AUX_ADC_TIC";
99"P3V3_PDB_AUX_ADC_TIC"CDS_PHYS_NET_NAME"P3V3_PDB_AUX_ADC_TIC";
100"SMB_SEN_TIC_3V3AUX_SDA"CDS_PHYS_NET_NAME"SMB_SEN_TIC_3V3AUX_SDA";
101"P12V_OCP_SFF_ISENSE_MAM_TIC"CDS_PHYS_NET_NAME"P12V_OCP_SFF_ISENSE_MAM_TIC";
102"ADC128_A0"CDS_PHYS_NET_NAME"ADC128_A0";
103"ADC128_A1"CDS_PHYS_NET_NAME"ADC128_A1";
104"SMB_SCM_2_R4_SDA"CDS_PHYS_NET_NAME"SMB_VR_3V3AUX_SDA_R1";
105"SMB_SEN_TIC_3V3AUX_SDA"CDS_PHYS_NET_NAME"SMB_SEN_TIC_3V3AUX_SDA";
106"SMB_SCM_2_R4_SCL"CDS_PHYS_NET_NAME"SMB_VR_3V3AUX_SCL_R1";
107"SMB_SEN_TIC_3V3AUX_SCL"CDS_PHYS_NET_NAME"SMB_SEN_TIC_3V3AUX_SCL";
108"P5V_ADC_TIC"CDS_PHYS_NET_NAME"P5V_ADC_TIC";
109"TP_ADC128_INT"CDS_PHYS_NET_NAME"TP_ADC128_INT";
110"P12V_OCP_V3_2_ISENSE_MAM_MAM"CDS_PHYS_NET_NAME"P12V_OCP_V3_2_ISENSE_MAM_MAM";
111"P3V3_PDB_AUX_ADC_MAM"CDS_PHYS_NET_NAME"P3V3_PDB_AUX_ADC_MAM";
%"UNIVERSAL_GND"
"1","(-8375,725)","0","pure_quanta_power","I1";
;
CDS_LIB"pure_quanta_power"
HDL_POWER"GND";
"A"1;
%"Q_RES"
"1","(-8100,2200)","0","pure_quanta","I10";
;
LOCATION"R3679"
$SEC"1"
CDS_SEC"1"
VALUE"0"
TOLERANCE"5%"
MATERIAL"EMPTY"
ROOM"ADC_MAM_BOM2"
CDS_LIB"pure_quanta"
WATTAGE"1/16W"
PACK_TYPE"0402LF"
PART_NUMBER"CS00002JB13";
"B"
$PN"2"69;
"A"
$PN"1"72;
%"Q_RES"
"1","(-5675,5025)","0","pure_quanta","I107";
;
LOCATION"R3859"
$SEC"1"
CDS_SEC"1"
VALUE"0"
TOLERANCE"5%"
MATERIAL"EMPTY"
CDS_LIB"pure_quanta"
WATTAGE"1/16W"
PACK_TYPE"0402LF"
PART_NUMBER"CS00002JB13";
"B"
$PN"2"54;
"A"
$PN"1"110;
%"Q_RES"
"1","(-5650,5350)","0","pure_quanta","I108";
;
LOCATION"R3866"
$SEC"1"
CDS_SEC"1"
TOLERANCE"5%"
ROOM"ADC_TI_BOM3"
VALUE"0"
MATERIAL"EMPTY"
PACK_TYPE"0402LF"
WATTAGE"1/16W"
CDS_LIB"pure_quanta"
PART_NUMBER"CS00002JB13";
"B"
$PN"2"56;
"A"
$PN"1"57;
%"Q_RES"
"1","(-5650,5500)","0","pure_quanta","I109";
;
LOCATION"R3865"
$SEC"1"
CDS_SEC"1"
VALUE"0"
ROOM"ADC_TI_BOM1"
TOLERANCE"5%"
MATERIAL"CHIP"
PACK_TYPE"0402LF"
WATTAGE"1/16W"
CDS_LIB"pure_quanta"
PART_NUMBER"CS00002JB13";
"B"
$PN"2"56;
"A"
$PN"1"101;
%"UNIVERSAL_GND"
"1","(-7925,2800)","0","pure_quanta_power","I11";
;
CDS_LIB"pure_quanta_power"
HDL_POWER"GND";
"A"2;
%"Q_RES"
"1","(-5650,5850)","0","pure_quanta","I110";
;
LOCATION"R3864"
$SEC"1"
CDS_SEC"1"
ROOM"ADC_MAM_BOM2"
MATERIAL"EMPTY"
VALUE"0"
TOLERANCE"5%"
PACK_TYPE"0402LF"
WATTAGE"1/16W"
CDS_LIB"pure_quanta"
PART_NUMBER"CS00002JB13";
"B"
$PN"2"42;
"A"
$PN"1"55;
%"UNIVERSAL_GND"
"1","(-4950,5150)","0","pure_quanta_power","I111";
;
CDS_LIB"pure_quanta_power"
HDL_POWER"GND";
"A"3;
%"Q_CAP"
"1","(-4950,5325)","2","pure_quanta","I112";
;
LOCATION"C37"
$SEC"1"
CDS_SEC"1"
VOLTAGE"25V"
TOLERANCE"10%"
VALUE"0.1UF"
PACK_TYPE"0402"
MATERIAL"X7R"
ROOM"ADC_TI_BOM1"
CDS_LIB"pure_quanta"
PART_NUMBER"CH4104K1B00";
"B"
$PN"2"3;
"A"
$PN"1"56;
%"UNIVERSAL_GND"
"1","(-4925,5650)","0","pure_quanta_power","I113";
;
CDS_LIB"pure_quanta_power"
HDL_POWER"GND";
"A"4;
%"Q_CAP"
"1","(-4925,5850)","0","pure_quanta","I114";
;
LOCATION"C2176"
$SEC"1"
CDS_SEC"1"
MATERIAL"EMPTY"
TOLERANCE"5%"
VALUE"100PF"
ROOM"ADC_MAM_BOM2"
PACK_TYPE"0402"
VOLTAGE"50V"
CDS_LIB"pure_quanta"
PART_NUMBER"CH11006JB18";
"B"
$PN"2"4;
"A"
$PN"1"42;
%"Q_RES"
"1","(-5650,6000)","0","pure_quanta","I115";
;
LOCATION"R3863"
$SEC"1"
CDS_SEC"1"
MATERIAL"EMPTY"
TOLERANCE"5%"
VALUE"0"
CDS_LIB"pure_quanta"
WATTAGE"1/16W"
PACK_TYPE"0402LF"
PART_NUMBER"CS00002JB13";
"B"
$PN"2"42;
"A"
$PN"1"67;
%"UNIVERSAL_GND"
"1","(-4200,5150)","0","pure_quanta_power","I118";
;
CDS_LIB"pure_quanta_power"
HDL_POWER"GND";
"A"5;
%"Q_CAP"
"1","(-4200,5350)","2","pure_quanta","I119";
;
LOCATION"C1347"
$SEC"1"
CDS_SEC"1"
VALUE"0.1UF"
VOLTAGE"25V"
TOLERANCE"10%"
PACK_TYPE"0402"
MATERIAL"X7R"
CDS_LIB"pure_quanta"
PART_NUMBER"CH4104K1B00";
"B"
$PN"2"5;
"A"
$PN"1"60;
%"UNIVERSAL_GND"
"1","(-8900,4175)","0","pure_quanta_power","I12";
;
CDS_LIB"pure_quanta_power"
HDL_POWER"GND";
"A"6;
%"UNIVERSAL_GND"
"1","(-3825,5150)","0","pure_quanta_power","I120";
;
CDS_LIB"pure_quanta_power"
HDL_POWER"GND";
"A"7;
%"Q_CAP"
"1","(-3825,5350)","0","pure_quanta","I121";
;
LOCATION"C1767"
$SEC"1"
CDS_SEC"1"
PACK_TYPE"C0805"
VOLTAGE"16V"
TOLERANCE"10%"
VALUE"10UF"
MATERIAL"X6S"
CDS_LIB"pure_quanta"
PART_NUMBER"CH6103KEA00";
"B"
$PN"2"7;
"A"
$PN"1"60;
%"UNIVERSAL_GND"
"1","(-3475,1675)","0","pure_quanta_power","I125";
;
CDS_LIB"pure_quanta_power"
HDL_POWER"GND";
"A"8;
%"UNIVERSAL_GND"
"1","(-8900,2900)","0","pure_quanta_power","I13";
;
CDS_LIB"pure_quanta_power"
HDL_POWER"GND";
"A"9;
%"Q_RES"
"2","(-3475,2000)","0","pure_quanta","I130";
;
LOCATION"R3690"
$SEC"1"
CDS_SEC"1"
PACK_TYPE"0402LF"
WATTAGE"1/16W"
TOLERANCE"1%"
MATERIAL"EMPTY"
VALUE"4.7K"
ROOM"ADC_TI_BOM1"
CDS_LIB"pure_quanta"
PART_NUMBER"CS24702FB06";
"A"
$PN"1"50;
"B"
$PN"2"8;
%"Q_RES"
"2","(-3475,2500)","0","pure_quanta","I131";
;
LOCATION"R3689"
$SEC"1"
CDS_SEC"1"
WATTAGE"1/16W"
MATERIAL"EMPTY"
TOLERANCE"1%"
PACK_TYPE"0402LF"
VALUE"4.7K"
ROOM"ADC_TI_BOM1"
CDS_LIB"pure_quanta"
PART_NUMBER"CS24702FB06";
"A"
$PN"1"92;
"B"
$PN"2"50;
%"Q_RES"
"2","(-8900,3200)","0","pure_quanta","I14";
;
LOCATION"R1791"
$SEC"1"
CDS_SEC"1"
MATERIAL"CHIP"
WATTAGE"1/16W"
TOLERANCE"1%"
VALUE"9.09K"
PACK_TYPE"0402LF"
CDS_LIB"pure_quanta"
PART_NUMBER"CS29092FB05";
"A"
$PN"1"48;
"B"
$PN"2"9;
%"ADC128D818CIMTXNOPB"
"1","(-1625,2100)","0","pure_quanta","I142";
;
LOCATION"U269"
$SEC"1"
CDS_SEC"1"
VALUE"ADC128D818CIMTX/NOPB"
MATERIAL"IC"
PART_TYPE"SMLF"
ROOM"ADC_TI_BOM1"
PIN_NAMES_ROTATE"True"
CDS_LMAN_SYM_OUTLINE"-250,475,250,-475"
CDS_LIB"pure_quanta"
PART_NUMBER"AL000128K00";
"INT# \B"
$PN"6"109;
"GND"
$PN"4"10;
"SCL"
$PN"3"95;
"SDA"
$PN"2"100;
"IN0"
$PN"16"93;
"IN1"
$PN"15"94;
"IN2"
$PN"14"96;
"IN3"
$PN"13"108;
"IN4"
$PN"12"97;
"IN5"
$PN"11"98;
"IN6"
$PN"10"99;
"IN7"
$PN"9"53;
"A1"
$PN"8"51;
"A0"
$PN"7"52;
"V+"
$PN"5"92;
"VREF"
$PN"1"50;
%"UNIVERSAL_GND"
"1","(-2925,4250)","0","pure_quanta_power","I145";
;
CDS_LIB"pure_quanta_power"
HDL_POWER"GND";
"A"61;
%"Q_RES"
"1","(-2400,3700)","0","pure_quanta","I146";
;
LOCATION"R1792"
$SEC"1"
CDS_SEC"1"
VALUE"0"
WATTAGE"1/16W"
PACK_TYPE"0402LF"
TOLERANCE"5%"
ROOM"ADC_MAM_BOM2"
MATERIAL"EMPTY"
CDS_LIB"pure_quanta"
PART_NUMBER"CS00002JB13";
"B"
$PN"2"85;
"A"
$PN"1"86;
%"Q_RES"
"1","(-2400,3650)","0","pure_quanta","I147";
;
LOCATION"R1793"
$SEC"1"
CDS_SEC"1"
ROOM"ADC_MAM_BOM2"
VALUE"0"
TOLERANCE"5%"
MATERIAL"EMPTY"
CDS_LIB"pure_quanta"
PACK_TYPE"0402LF"
WATTAGE"1/16W"
PART_NUMBER"CS00002JB13";
"B"
$PN"2"62;
"A"
$PN"1"87;
%"UNIVERSAL_GND"
"1","(-1900,4300)","0","pure_quanta_power","I148";
;
CDS_LIB"pure_quanta_power"
HDL_POWER"GND";
"A"63;
%"Q_RES"
"1","(-1550,1050)","0","pure_quanta","I149";
;
LOCATION"R3671"
$SEC"1"
CDS_SEC"1"
VALUE"0"
TOLERANCE"5%"
WATTAGE"1/16W"
PACK_TYPE"0402LF"
MATERIAL"CHIP"
ROOM"ADC_TI_BOM1"
CDS_LIB"pure_quanta"
PART_NUMBER"CS00002JB13";
"B"
$PN"2"105;
"A"
$PN"1"104;
%"Q_RES"
"2","(-8900,3750)","0","pure_quanta","I15";
;
LOCATION"R3005"
$SEC"1"
CDS_SEC"1"
TOLERANCE"1%"
VALUE"18K"
PACK_TYPE"0402LF"
WATTAGE"1/16W"
MATERIAL"CHIP"
CDS_LIB"pure_quanta"
PART_NUMBER"CS31802FB04";
"A"
$PN"1"14;
"B"
$PN"2"48;
%"Q_RES"
"1","(-1550,1000)","0","pure_quanta","I150";
;
LOCATION"R3672"
$SEC"1"
CDS_SEC"1"
VALUE"0"
TOLERANCE"5%"
MATERIAL"CHIP"
ROOM"ADC_TI_BOM1"
PACK_TYPE"0402LF"
CDS_LIB"pure_quanta"
WATTAGE"1/16W"
PART_NUMBER"CS00002JB13";
"B"
$PN"2"107;
"A"
$PN"1"106;
%"UNIVERSAL_GND"
"1","(-1050,1475)","0","pure_quanta_power","I151";
;
CDS_LIB"pure_quanta_power"
HDL_POWER"GND";
"A"10;
%"Q_RES"
"1","(-8275,3350)","0","pure_quanta","I16";
;
LOCATION"R3686"
$SEC"1"
CDS_SEC"1"
ROOM"ADC_TI_BOM1"
TOLERANCE"5%"
VALUE"0"
MATERIAL"CHIP"
CDS_LIB"pure_quanta"
WATTAGE"1/16W"
PACK_TYPE"0402LF"
PART_NUMBER"CS00002JB13";
"B"
$PN"2"73;
"A"
$PN"1"48;
%"Q_RES"
"1","(-3475,5525)","0","pure_quanta","I160";
;
LOCATION"R2900"
$SEC"1"
CDS_SEC"1"
WATTAGE"1/16W"
VALUE"2K"
TOLERANCE"1%"
PACK_TYPE"0402LF"
MATERIAL"CHIP"
CDS_LIB"pure_quanta"
PART_NUMBER"CS22002FB07";
"B"
$PN"2"59;
"A"
$PN"1"60;
%"UNIVERSAL_GND"
"1","(-1500,5150)","0","pure_quanta_power","I161";
;
CDS_LIB"pure_quanta_power"
HDL_POWER"GND";
"A"11;
%"Q_CAP"
"1","(-1500,5325)","2","pure_quanta","I162";
;
LOCATION"C1757"
$SEC"1"
CDS_SEC"1"
PACK_TYPE"0402"
VOLTAGE"25V"
VALUE"0.1UF"
MATERIAL"X7R"
TOLERANCE"10%"
CDS_LIB"pure_quanta"
PART_NUMBER"CH4104K1B00";
"B"
$PN"2"11;
"A"
$PN"1"58;
%"UNIVERSAL_GND"
"1","(-1125,5150)","0","pure_quanta_power","I163";
;
CDS_LIB"pure_quanta_power"
HDL_POWER"GND";
"A"12;
%"Q_CAP"
"1","(-1125,5325)","0","pure_quanta","I166";
;
LOCATION"C1768"
$SEC"1"
CDS_SEC"1"
VALUE"10UF"
PACK_TYPE"C0805"
TOLERANCE"10%"
VOLTAGE"16V"
MATERIAL"X6S"
CDS_LIB"pure_quanta"
PART_NUMBER"CH6103KEA00";
"B"
$PN"2"12;
"A"
$PN"1"58;
%"Q_INDUCTOR"
"1","(-800,5550)","0","pure_quanta","I167";
;
LOCATION"L15"
$SEC"1"
CDS_SEC"1"
VALUE"BLM18PG300SN1D "
PACK_TYPE"SMLF"
MATERIAL"IND"
CDS_LIB"pure_quanta"
NEEDS_NO_SIZE"TRUE"
PART_NUMBER"TMP_QCX8PG300001";
"1"
$PN"1"58;
"2"
$PN"2"13;
%"UNIVERSAL_POWER"
"1","(-375,5750)","0","pure_quanta_power","I168";
;
HDL_POWER"P3V3_AUX"
CDS_LIB"pure_quanta_power";
"A"13;
%"MAX11617EEET"
"1","(-2425,4900)","0","pure_quanta","I169";
;
LOCATION"U193"
SEC"1"
MATERIAL"EMPTY"
ROOM"ADC_MAM_BOM2"
VALUE"MAX11617EEE+T"
PART_TYPE"SMLF"
SEC_TYPE""
CDS_LMAN_SYM_OUTLINE"-250,400,250,-400"
NEEDS_NO_SIZE"TRUE"
CDS_LIB"pure_quanta"
PART_NUMBER"AL011617W00";
"VDD"
$PN"16"58;
"GND"
$PN"15"63;
"SDA"
$PN"14"84;
"SCL"
$PN"13"83;
"AIN7"
$PN"12"82;
"AIN6"
$PN"11"111;
"AIN5"
$PN"10"80;
"AIN4"
$PN"9"81;
"AIN3"
$PN"8"88;
"AIN2"
$PN"7"91;
"AIN1"
$PN"6"89;
"AIN0"
$PN"5"90;
"AIN8"
$PN"4"61;
"AIN9"
$PN"3"61;
"AIN10"
$PN"2"61;
"AIN11||REF"
$PN"1"59;
%"Q_CAP"
"1","(-7925,3075)","2","pure_quanta","I17";
;
LOCATION"C2049"
$SEC"1"
CDS_SEC"1"
VALUE"0.1UF"
VOLTAGE"25V"
TOLERANCE"10%"
MATERIAL"X7R"
PACK_TYPE"0402"
ROOM"ADC_TI_BOM1"
CDS_LIB"pure_quanta"
PART_NUMBER"CH4104K1B00";
"B"
$PN"2"2;
"A"
$PN"1"73;
%"Q_RES"
"2","(-8925,2000)","0","pure_quanta","I170";
;
LOCATION"R1800"
SEC"1"
TOLERANCE"1%"
MATERIAL"CHIP"
PACK_TYPE"0402LF"
WATTAGE"1/16W"
VALUE"1.21K"
CDS_LIB"pure_quanta"
SEC_TYPE"0402LF"
PART_NUMBER"CS21212FB05";
"A"
$PN"1"72;
"B"
$PN"2"18;
%"Q_RES"
"1","(-8275,3500)","0","pure_quanta","I18";
;
LOCATION"R3685"
$SEC"1"
CDS_SEC"1"
VALUE"0"
ROOM"ADC_MAM_BOM2"
MATERIAL"EMPTY"
TOLERANCE"5%"
CDS_LIB"pure_quanta"
WATTAGE"1/16W"
PACK_TYPE"0402LF"
PART_NUMBER"CS00002JB13";
"B"
$PN"2"41;
"A"
$PN"1"48;
%"UNIVERSAL_POWER"
"1","(-8900,4000)","0","pure_quanta_power","I19";
;
HDL_POWER"P5V"
CDS_LIB"pure_quanta_power";
"A"14;
%"Q_RES"
"2","(-8900,4425)","0","pure_quanta","I20";
;
LOCATION"R2843"
$SEC"1"
CDS_SEC"1"
PACK_TYPE"0402LF"
WATTAGE"1/16W"
MATERIAL"CHIP"
TOLERANCE"1%"
VALUE"4.7K"
CDS_LIB"pure_quanta"
PART_NUMBER"CS24702FB06";
"A"
$PN"1"78;
"B"
$PN"2"6;
%"Q_RES"
"2","(-8900,4900)","0","pure_quanta","I21";
;
LOCATION"R2908"
$SEC"1"
CDS_SEC"1"
PACK_TYPE"0402LF"
TOLERANCE"1%"
WATTAGE"1/16W"
VALUE"5.11K"
MATERIAL"CHIP"
CDS_LIB"pure_quanta"
PART_NUMBER"CS25112FB04";
"A"
$PN"1"16;
"B"
$PN"2"78;
%"Q_RES"
"1","(-8275,4500)","0","pure_quanta","I22";
;
LOCATION"R3684"
$SEC"1"
CDS_SEC"1"
MATERIAL"CHIP"
VALUE"0"
TOLERANCE"5%"
ROOM"ADC_TI_BOM1"
PACK_TYPE"0402LF"
WATTAGE"1/16W"
CDS_LIB"pure_quanta"
PART_NUMBER"CS00002JB13";
"B"
$PN"2"75;
"A"
$PN"1"78;
%"Q_RES"
"1","(-8275,4650)","0","pure_quanta","I23";
;
LOCATION"R3683"
$SEC"1"
CDS_SEC"1"
MATERIAL"EMPTY"
TOLERANCE"5%"
VALUE"0"
ROOM"ADC_MAM_BOM2"
PACK_TYPE"0402LF"
WATTAGE"1/16W"
CDS_LIB"pure_quanta"
PART_NUMBER"CS00002JB13";
"B"
$PN"2"74;
"A"
$PN"1"78;
%"UNIVERSAL_GND"
"1","(-8900,5350)","0","pure_quanta_power","I24";
;
CDS_LIB"pure_quanta_power"
HDL_POWER"GND";
"A"15;
%"UNIVERSAL_POWER"
"1","(-8900,5150)","0","pure_quanta_power","I25";
;
HDL_POWER"P3V3"
CDS_LIB"pure_quanta_power";
"A"16;
%"Q_RES"
"2","(-8900,5700)","0","pure_quanta","I26";
;
LOCATION"R1785"
$SEC"1"
CDS_SEC"1"
WATTAGE"1/16W"
PACK_TYPE"0402LF"
TOLERANCE"1%"
VALUE"4.7K"
MATERIAL"CHIP"
CDS_LIB"pure_quanta"
PART_NUMBER"CS24702FB06";
"A"
$PN"1"79;
"B"
$PN"2"15;
%"Q_RES"
"1","(-8200,5825)","0","pure_quanta","I27";
;
LOCATION"R3682"
$SEC"1"
CDS_SEC"1"
MATERIAL"CHIP"
TOLERANCE"5%"
VALUE"0"
ROOM"ADC_TI_BOM1"
CDS_LIB"pure_quanta"
WATTAGE"1/16W"
PACK_TYPE"0402LF"
PART_NUMBER"CS00002JB13";
"B"
$PN"2"76;
"A"
$PN"1"79;
%"Q_RES"
"2","(-8900,6225)","0","pure_quanta","I28";
;
LOCATION"R2907"
$SEC"1"
CDS_SEC"1"
PACK_TYPE"0402LF"
MATERIAL"CHIP"
VALUE"5.11K"
TOLERANCE"1%"
WATTAGE"1/16W"
CDS_LIB"pure_quanta"
PART_NUMBER"CS25112FB04";
"A"
$PN"1"17;
"B"
$PN"2"79;
%"UNIVERSAL_POWER"
"1","(-8900,6475)","0","pure_quanta_power","I29";
;
HDL_POWER"P3V3_AUX"
CDS_LIB"pure_quanta_power";
"A"17;
%"UNIVERSAL_GND"
"1","(-8925,1700)","0","pure_quanta_power","I3";
;
CDS_LIB"pure_quanta_power"
HDL_POWER"GND";
"A"18;
%"Q_RES"
"1","(-8200,5975)","0","pure_quanta","I30";
;
LOCATION"R3681"
$SEC"1"
CDS_SEC"1"
ROOM"ADC_MAM_BOM2"
MATERIAL"EMPTY"
VALUE"0"
TOLERANCE"5%"
CDS_LIB"pure_quanta"
WATTAGE"1/16W"
PACK_TYPE"0402LF"
PART_NUMBER"CS00002JB13";
"B"
$PN"2"77;
"A"
$PN"1"79;
%"UNIVERSAL_GND"
"1","(-7900,3950)","0","pure_quanta_power","I31";
;
CDS_LIB"pure_quanta_power"
HDL_POWER"GND";
"A"19;
%"Q_CAP"
"1","(-7900,4225)","2","pure_quanta","I32";
;
LOCATION"C2048"
$SEC"1"
CDS_SEC"1"
VOLTAGE"25V"
MATERIAL"X7R"
ROOM"ADC_TI_BOM1"
PACK_TYPE"0402"
TOLERANCE"10%"
VALUE"0.1UF"
CDS_LIB"pure_quanta"
PART_NUMBER"CH4104K1B00";
"B"
$PN"2"19;
"A"
$PN"1"75;
%"UNIVERSAL_GND"
"1","(-6875,625)","0","pure_quanta_power","I33";
;
CDS_LIB"pure_quanta_power"
HDL_POWER"GND";
"A"20;
%"Q_CAP"
"1","(-6875,875)","2","pure_quanta","I34";
;
LOCATION"C2050"
$SEC"1"
CDS_SEC"1"
VALUE"0.1UF"
PACK_TYPE"0402"
TOLERANCE"10%"
VOLTAGE"25V"
MATERIAL"X7R"
ROOM"ADC_TI_BOM1"
CDS_LIB"pure_quanta"
PART_NUMBER"CH4104K1B00";
"B"
$PN"2"20;
"A"
$PN"1"37;
%"UNIVERSAL_GND"
"1","(-6525,600)","0","pure_quanta_power","I35";
;
CDS_LIB"pure_quanta_power"
HDL_POWER"GND";
"A"21;
%"Q_CAP"
"1","(-6525,875)","0","pure_quanta","I36";
;
LOCATION"C2045"
$SEC"1"
CDS_SEC"1"
ROOM"ADC_MAM_BOM2"
MATERIAL"EMPTY"
PACK_TYPE"0402"
TOLERANCE"5%"
VOLTAGE"50V"
VALUE"100PF"
CDS_LIB"pure_quanta"
PART_NUMBER"CH11006JB18";
"B"
$PN"2"21;
"A"
$PN"1"36;
%"UNIVERSAL_GND"
"1","(-4550,500)","0","pure_quanta_power","I37";
;
CDS_LIB"pure_quanta_power"
HDL_POWER"GND";
"A"22;
%"Q_RES"
"2","(-4550,725)","0","pure_quanta","I38";
;
LOCATION"R3668"
$SEC"1"
CDS_SEC"1"
ROOM"ADC_TI_BOM1"
WATTAGE"1/16W"
MATERIAL"CHIP"
TOLERANCE"1%"
VALUE"1K"
PACK_TYPE"0402LF"
CDS_LIB"pure_quanta"
PART_NUMBER"CS21002FB06";
"A"
$PN"1"103;
"B"
$PN"2"22;
%"UNIVERSAL_GND"
"1","(-4300,500)","0","pure_quanta_power","I39";
;
CDS_LIB"pure_quanta_power"
HDL_POWER"GND";
"A"23;
%"Q_RES"
"2","(-4300,725)","0","pure_quanta","I40";
;
LOCATION"R3670"
$SEC"1"
CDS_SEC"1"
ROOM"ADC_TI_BOM1"
VALUE"1K"
TOLERANCE"1%"
PACK_TYPE"0402LF"
MATERIAL"CHIP"
WATTAGE"1/16W"
CDS_LIB"pure_quanta"
PART_NUMBER"CS21002FB06";
"A"
$PN"1"102;
"B"
$PN"2"23;
%"Q_RES"
"1","(-7425,1150)","0","pure_quanta","I41";
;
LOCATION"R3688"
$SEC"1"
CDS_SEC"1"
TOLERANCE"5%"
MATERIAL"CHIP"
VALUE"0"
ROOM"ADC_TI_BOM1"
PACK_TYPE"0402LF"
WATTAGE"1/16W"
CDS_LIB"pure_quanta"
PART_NUMBER"CS00002JB13";
"B"
$PN"2"37;
"A"
$PN"1"68;
%"Q_RES"
"1","(-7425,1300)","0","pure_quanta","I42";
;
LOCATION"R3687"
$SEC"1"
CDS_SEC"1"
TOLERANCE"5%"
MATERIAL"EMPTY"
VALUE"0"
ROOM"ADC_MAM_BOM2"
PACK_TYPE"0402LF"
WATTAGE"1/16W"
CDS_LIB"pure_quanta"
PART_NUMBER"CS00002JB13";
"B"
$PN"2"36;
"A"
$PN"1"68;
%"UNIVERSAL_GND"
"1","(-7550,1500)","0","pure_quanta_power","I43";
;
CDS_LIB"pure_quanta_power"
HDL_POWER"GND";
"A"24;
%"Q_CAP"
"1","(-7550,1775)","2","pure_quanta","I44";
;
LOCATION"C2046"
$SEC"1"
CDS_SEC"1"
PACK_TYPE"0402"
MATERIAL"X7R"
VALUE"0.1UF"
VOLTAGE"25V"
TOLERANCE"10%"
ROOM"ADC_TI_BOM1"
CDS_LIB"pure_quanta"
PART_NUMBER"CH4104K1B00";
"B"
$PN"2"24;
"A"
$PN"1"71;
%"UNIVERSAL_GND"
"1","(-7200,1500)","0","pure_quanta_power","I45";
;
CDS_LIB"pure_quanta_power"
HDL_POWER"GND";
"A"25;
%"Q_CAP"
"1","(-7200,1775)","0","pure_quanta","I46";
;
LOCATION"C1344"
$SEC"1"
CDS_SEC"1"
VOLTAGE"50V"
MATERIAL"EMPTY"
PACK_TYPE"0402"
TOLERANCE"5%"
VALUE"100PF"
ROOM"ADC_MAM_BOM2"
CDS_LIB"pure_quanta"
PART_NUMBER"CH11006JB18";
"B"
$PN"2"25;
"A"
$PN"1"69;
%"UNIVERSAL_GND"
"1","(-7575,2800)","0","pure_quanta_power","I47";
;
CDS_LIB"pure_quanta_power"
HDL_POWER"GND";
"A"26;
%"UNIVERSAL_POWER"
"1","(-8925,2700)","0","pure_quanta_power","I5";
;
HDL_POWER"P12V_AUX"
CDS_LIB"pure_quanta_power";
"A"27;
%"Q_CAP"
"1","(-7575,3075)","0","pure_quanta","I52";
;
LOCATION"C2044"
$SEC"1"
CDS_SEC"1"
ROOM"ADC_MAM_BOM2"
PACK_TYPE"0402"
MATERIAL"EMPTY"
TOLERANCE"5%"
VOLTAGE"50V"
VALUE"100PF"
CDS_LIB"pure_quanta"
PART_NUMBER"CH11006JB18";
"B"
$PN"2"26;
"A"
$PN"1"41;
%"Q_CAP"
"1","(-7550,4225)","0","pure_quanta","I55";
;
LOCATION"C2043"
$SEC"1"
CDS_SEC"1"
VALUE"100PF"
VOLTAGE"50V"
TOLERANCE"5%"
MATERIAL"EMPTY"
PACK_TYPE"0402"
ROOM"ADC_MAM_BOM2"
CDS_LIB"pure_quanta"
PART_NUMBER"CH11006JB18";
"B"
$PN"2"28;
"A"
$PN"1"74;
%"UNIVERSAL_GND"
"1","(-7550,3950)","0","pure_quanta_power","I56";
;
CDS_LIB"pure_quanta_power"
HDL_POWER"GND";
"A"28;
%"Q_RES"
"2","(-8925,2450)","0","pure_quanta","I6";
;
LOCATION"R1799"
$SEC"1"
CDS_SEC"1"
VALUE"7.87K"
WATTAGE"1/16W"
TOLERANCE"1%"
MATERIAL"CHIP"
PACK_TYPE"0402LF"
CDS_LIB"pure_quanta"
PART_NUMBER"CS27872FB02";
"A"
$PN"1"27;
"B"
$PN"2"72;
%"Q_RES"
"2","(-4550,1325)","0","pure_quanta","I66";
;
LOCATION"R3667"
$SEC"1"
CDS_SEC"1"
ROOM"ADC_TI_BOM1"
PACK_TYPE"0402LF"
VALUE"1K"
MATERIAL"EMPTY"
TOLERANCE"1%"
WATTAGE"1/16W"
CDS_LIB"pure_quanta"
PART_NUMBER"CS21002FB06";
"A"
$PN"1"64;
"B"
$PN"2"103;
%"UNIVERSAL_POWER"
"1","(-4550,1725)","0","pure_quanta_power","I67";
;
HDL_POWER"P3V3_AUX"
CDS_LIB"pure_quanta_power";
"A"64;
%"Q_RES"
"2","(-4300,1325)","0","pure_quanta","I68";
;
LOCATION"R3669"
$SEC"1"
CDS_SEC"1"
MATERIAL"EMPTY"
PACK_TYPE"0402LF"
VALUE"1K"
TOLERANCE"1%"
WATTAGE"1/16W"
ROOM"ADC_TI_BOM1"
CDS_LIB"pure_quanta"
PART_NUMBER"CS21002FB06";
"A"
$PN"1"64;
"B"
$PN"2"102;
%"Q_INDUCTOR"
"1","(-4350,2725)","0","pure_quanta","I69";
;
LOCATION"L16"
$SEC"1"
CDS_SEC"1"
MATERIAL"IND"
PACK_TYPE"SMLF"
VALUE"BLM18PG300SN1D "
ROOM"ADC_TI_BOM1"
NEEDS_NO_SIZE"TRUE"
CDS_LIB"pure_quanta"
PART_NUMBER"TMP_QCX8PG300001";
"1"
$PN"1"33;
"2"
$PN"2"92;
%"Q_RES"
"2","(-8375,950)","0","pure_quanta","I7";
;
LOCATION"R4568"
$SEC"1"
CDS_SEC"1"
TOLERANCE"1%"
VALUE"4.7K"
MATERIAL"CHIP"
WATTAGE"1/16W"
PACK_TYPE"0402LF"
CDS_LIB"pure_quanta"
PART_NUMBER"CS24702FB06";
"A"
$PN"1"68;
"B"
$PN"2"1;
%"UNIVERSAL_GND"
"1","(-4175,2175)","0","pure_quanta_power","I70";
;
CDS_LIB"pure_quanta_power"
HDL_POWER"GND";
"A"65;
%"Q_CAP"
"1","(-4175,2500)","2","pure_quanta","I71";
;
LOCATION"C2051"
$SEC"1"
CDS_SEC"1"
TOLERANCE"10%"
ROOM"ADC_TI_BOM1"
VOLTAGE"25V"
MATERIAL"X7R"
VALUE"0.1UF"
PACK_TYPE"0402"
CDS_LIB"pure_quanta"
PART_NUMBER"CH4104K1B00";
"B"
$PN"2"65;
"A"
$PN"1"92;
%"Q_CAP"
"1","(-3850,2500)","0","pure_quanta","I72";
;
LOCATION"C2052"
$SEC"1"
CDS_SEC"1"
MATERIAL"X7R"
VOLTAGE"25V"
VALUE"0.1UF"
TOLERANCE"10%"
ROOM"ADC_TI_BOM1"
PACK_TYPE"0402"
CDS_LIB"pure_quanta"
PART_NUMBER"CH4104K1B00";
"B"
$PN"2"65;
"A"
$PN"1"92;
%"Q_RES"
"1","(-5700,3375)","0","pure_quanta","I73";
;
LOCATION"R3942"
$SEC"1"
CDS_SEC"1"
TOLERANCE"5%"
VALUE"0"
MATERIAL"EMPTY"
ROOM"ADC_TI_BOM3"
PACK_TYPE"0402LF"
WATTAGE"1/16W"
CDS_LIB"pure_quanta"
PART_NUMBER"CS00002JB13";
"B"
$PN"2"38;
"A"
$PN"1"49;
%"Q_RES"
"1","(-5700,3525)","0","pure_quanta","I74";
;
LOCATION"R3941"
$SEC"1"
CDS_SEC"1"
TOLERANCE"5%"
VALUE"0"
MATERIAL"CHIP"
ROOM"ADC_TI_BOM1"
PACK_TYPE"0402LF"
WATTAGE"1/16W"
CDS_LIB"pure_quanta"
PART_NUMBER"CS00002JB13";
"B"
$PN"2"38;
"A"
$PN"1"47;
%"UNIVERSAL_GND"
"1","(-5000,3175)","0","pure_quanta_power","I75";
;
CDS_LIB"pure_quanta_power"
HDL_POWER"GND";
"A"29;
%"Q_CAP"
"1","(-5000,3350)","2","pure_quanta","I76";
;
LOCATION"C2194"
$SEC"1"
CDS_SEC"1"
ROOM"ADC_TI_BOM1"
TOLERANCE"10%"
MATERIAL"X7R"
VOLTAGE"25V"
PACK_TYPE"0402"
VALUE"0.1UF"
CDS_LIB"pure_quanta"
PART_NUMBER"CH4104K1B00";
"B"
$PN"2"29;
"A"
$PN"1"38;
%"UNIVERSAL_GND"
"1","(-4975,3675)","0","pure_quanta_power","I77";
;
CDS_LIB"pure_quanta_power"
HDL_POWER"GND";
"A"30;
%"Q_CAP"
"1","(-4975,3875)","0","pure_quanta","I78";
;
LOCATION"C35"
$SEC"1"
CDS_SEC"1"
PACK_TYPE"0402"
ROOM"ADC_MAM_BOM2"
MATERIAL"EMPTY"
VALUE"100PF"
VOLTAGE"50V"
TOLERANCE"5%"
CDS_LIB"pure_quanta"
PART_NUMBER"CH11006JB18";
"B"
$PN"2"30;
"A"
$PN"1"39;
%"Q_RES"
"1","(-5700,3875)","0","pure_quanta","I79";
;
LOCATION"R3940"
$SEC"1"
CDS_SEC"1"
TOLERANCE"5%"
MATERIAL"EMPTY"
VALUE"0"
ROOM"ADC_MAM_BOM2"
CDS_LIB"pure_quanta"
WATTAGE"1/16W"
PACK_TYPE"0402LF"
PART_NUMBER"CS00002JB13";
"B"
$PN"2"39;
"A"
$PN"1"46;
%"Q_RES"
"2","(-8375,1325)","0","pure_quanta","I8";
;
LOCATION"R4567"
$SEC"1"
CDS_SEC"1"
TOLERANCE"1%"
VALUE"5.11K"
PACK_TYPE"0402LF"
MATERIAL"CHIP"
WATTAGE"1/16W"
CDS_LIB"pure_quanta"
PART_NUMBER"CS25112FB04";
"A"
$PN"1"70;
"B"
$PN"2"68;
%"Q_RES"
"1","(-5700,4025)","0","pure_quanta","I80";
;
LOCATION"R3939"
$SEC"1"
CDS_SEC"1"
VALUE"0"
MATERIAL"EMPTY"
TOLERANCE"5%"
PACK_TYPE"0402LF"
WATTAGE"1/16W"
CDS_LIB"pure_quanta"
PART_NUMBER"CS00002JB13";
"B"
$PN"2"39;
"A"
$PN"1"45;
%"Q_RES"
"1","(-5675,4375)","0","pure_quanta","I81";
;
LOCATION"R3862"
$SEC"1"
CDS_SEC"1"
VALUE"0"
TOLERANCE"5%"
MATERIAL"EMPTY"
ROOM"ADC_TI_BOM3"
CDS_LIB"pure_quanta"
WATTAGE"1/16W"
PACK_TYPE"0402LF"
PART_NUMBER"CS00002JB13";
"B"
$PN"2"40;
"A"
$PN"1"44;
%"Q_RES"
"1","(-5675,4525)","0","pure_quanta","I82";
;
LOCATION"R3861"
$SEC"1"
CDS_SEC"1"
ROOM"ADC_TI_BOM1"
TOLERANCE"5%"
VALUE"0"
MATERIAL"CHIP"
PACK_TYPE"0402LF"
WATTAGE"1/16W"
CDS_LIB"pure_quanta"
PART_NUMBER"CS00002JB13";
"B"
$PN"2"40;
"A"
$PN"1"43;
%"Q_RES"
"1","(-5675,4875)","0","pure_quanta","I83";
;
LOCATION"R3860"
$SEC"1"
CDS_SEC"1"
MATERIAL"EMPTY"
TOLERANCE"5%"
VALUE"0"
ROOM"ADC_MAM_BOM2"
PACK_TYPE"0402LF"
WATTAGE"1/16W"
CDS_LIB"pure_quanta"
PART_NUMBER"CS00002JB13";
"B"
$PN"2"54;
"A"
$PN"1"66;
%"Q_CAP"
"1","(-4975,4350)","2","pure_quanta","I84";
;
LOCATION"C33"
$SEC"1"
CDS_SEC"1"
VALUE"0.1UF"
VOLTAGE"25V"
TOLERANCE"10%"
MATERIAL"X7R"
PACK_TYPE"0402"
ROOM"ADC_TI_BOM1"
CDS_LIB"pure_quanta"
PART_NUMBER"CH4104K1B00";
"B"
$PN"2"31;
"A"
$PN"1"40;
%"UNIVERSAL_GND"
"1","(-4975,4175)","0","pure_quanta_power","I85";
;
CDS_LIB"pure_quanta_power"
HDL_POWER"GND";
"A"31;
%"UNIVERSAL_GND"
"1","(-4950,4675)","0","pure_quanta_power","I86";
;
CDS_LIB"pure_quanta_power"
HDL_POWER"GND";
"A"32;
%"Q_CAP"
"1","(-4950,4875)","0","pure_quanta","I87";
;
LOCATION"C59"
$SEC"1"
CDS_SEC"1"
VOLTAGE"50V"
TOLERANCE"5%"
ROOM"ADC_MAM_BOM2"
VALUE"100PF"
MATERIAL"EMPTY"
PACK_TYPE"0402"
CDS_LIB"pure_quanta"
PART_NUMBER"CH11006JB18";
"B"
$PN"2"32;
"A"
$PN"1"54;
%"UNIVERSAL_POWER"
"1","(-4650,2950)","0","pure_quanta_power","I88";
;
HDL_POWER"P3V3_AUX"
CDS_LIB"pure_quanta_power";
"A"33;
%"Q_RES"
"1","(-8100,2050)","0","pure_quanta","I9";
;
LOCATION"R3680"
$SEC"1"
CDS_SEC"1"
MATERIAL"CHIP"
ROOM"ADC_TI_BOM1"
VALUE"0"
TOLERANCE"5%"
CDS_LIB"pure_quanta"
WATTAGE"1/16W"
PACK_TYPE"0402LF"
PART_NUMBER"CS00002JB13";
"B"
$PN"2"71;
"A"
$PN"1"72;
%"UNIVERSAL_GND"
"1","(-7825,5300)","0","pure_quanta_power","I96";
;
CDS_LIB"pure_quanta_power"
HDL_POWER"GND";
"A"34;
%"UNIVERSAL_GND"
"1","(-7475,5300)","0","pure_quanta_power","I97";
;
CDS_LIB"pure_quanta_power"
HDL_POWER"GND";
"A"35;
%"Q_CAP"
"1","(-7825,5575)","2","pure_quanta","I98";
;
LOCATION"C2047"
$SEC"1"
CDS_SEC"1"
PACK_TYPE"0402"
MATERIAL"X7R"
TOLERANCE"10%"
VOLTAGE"25V"
VALUE"0.1UF"
ROOM"ADC_TI_BOM1"
CDS_LIB"pure_quanta"
PART_NUMBER"CH4104K1B00";
"B"
$PN"2"34;
"A"
$PN"1"76;
%"Q_CAP"
"1","(-7475,5575)","0","pure_quanta","I99";
;
LOCATION"C2042"
$SEC"1"
CDS_SEC"1"
TOLERANCE"5%"
VALUE"100PF"
MATERIAL"EMPTY"
VOLTAGE"50V"
PACK_TYPE"0402"
ROOM"ADC_MAM_BOM2"
CDS_LIB"pure_quanta"
PART_NUMBER"CH11006JB18";
"B"
$PN"2"35;
"A"
$PN"1"77;
END.
